(kicad_pcb
	(version 20260206)
	(generator "pcbnew")
	(generator_version "10.0")
	(general
		(thickness 1.6)
		(legacy_teardrops no)
	)
	(paper "A4")
	(title_block
		(title "dpb — 14545-sa.0730WZS0815.brd")
		(comment 1 "Honey Badger (Wiwynn) / footprints 448-454 of 1066")
	)
	(layers
		(0 "F.Cu" signal "TOP")
		(4 "In1.Cu" signal "L2GND")
		(6 "In2.Cu" signal "L3")
		(8 "In3.Cu" signal "L4VCC")
		(10 "In4.Cu" signal "L5VCC")
		(12 "In5.Cu" signal "L6")
		(14 "In6.Cu" signal "L7GND")
		(2 "B.Cu" signal "BOTTOM")
		(9 "F.Adhes" user "F.Adhesive")
		(11 "B.Adhes" user "B.Adhesive")
		(13 "F.Paste" user "Package Geometry/Pastemask Top")
		(15 "B.Paste" user "Package Geometry/Pastemask Bottom")
		(5 "F.SilkS" user "Ref Des/Silkscreen Top")
		(7 "B.SilkS" user "Ref Des/Silkscreen Bottom")
		(1 "F.Mask" user "Board Geometry/Soldermask Top")
		(3 "B.Mask" user "Board Geometry/Soldermask Bottom")
		(17 "Dwgs.User" user "User.Drawings")
		(19 "Cmts.User" user "User.Comments")
		(21 "Eco1.User" user "User.Eco1")
		(23 "Eco2.User" user "User.Eco2")
		(25 "Edge.Cuts" user "Board Geometry/Outline")
		(27 "Margin" user)
		(31 "F.CrtYd" user "Package Geometry/Place Bound Top")
		(29 "B.CrtYd" user "Package Geometry/Place Bound Bottom")
		(35 "F.Fab" user "Ref Des/Assembly Top")
		(33 "B.Fab" user "Ref Des/Assembly Bottom")
	)
	(footprint ""
		(layer "F.Cu")
		(at 36.83 -135.9662)
		(property "Reference" "Q73"
			(at 0 0 0)
			(layer "F.SilkS")
			(hide yes)
			(effects
				(font
					(size 1.27 1.27)
				)
			)
		)
		(property "Value" "2N7002-11-GP"
			(at 0.127 -8.9662 0)
			(unlocked yes)
			(layer "F.Fab")
			(hide yes)
			(effects
				(font
					(size 1.016 1.016)
					(thickness 0.1524)
				)
			)
		)
		(property "Device Type" "SOT23DGS2D4H44"
			(at 0.127 -10.4902 0)
			(unlocked yes)
			(layer "F.Fab")
			(hide yes)
			(effects
				(font
					(size 1.016 1.016)
					(thickness 0.1524)
				)
			)
		)
		(duplicate_pad_numbers_are_jumpers no)
		(fp_line
			(start -1.651 -1.778)
			(end -1.651 1.778)
			(stroke
				(width 0.1524)
				(type default)
			)
			(layer "F.SilkS")
		)
		(fp_line
			(start -1.651 1.778)
			(end 1.651 1.778)
			(stroke
				(width 0.1524)
				(type default)
			)
			(layer "F.SilkS")
		)
		(fp_line
			(start 1.651 -1.778)
			(end -1.651 -1.778)
			(stroke
				(width 0.1524)
				(type default)
			)
			(layer "F.SilkS")
		)
		(fp_line
			(start 1.651 1.778)
			(end 1.651 -1.778)
			(stroke
				(width 0.1524)
				(type default)
			)
			(layer "F.SilkS")
		)
		(fp_poly
			(pts
				(xy -1.778 1.8796) (xy -1.778 -1.8796) (xy 1.778 -1.8796) (xy 1.778 1.8796)
			)
			(stroke
				(width 0)
				(type default)
			)
			(fill no)
			(layer "F.CrtYd")
		)
		(fp_poly
			(pts
				(xy -1.778 1.8796) (xy -1.778 -1.8796) (xy 1.778 -1.8796) (xy 1.778 1.8796)
			)
			(stroke
				(width 0)
				(type default)
			)
			(fill no)
			(layer "F.Fab")
		)
		(pad "D" smd custom
			(at 0 -0.9525)
			(size 0.1905 0.1905)
			(layers "F.Cu" "F.Mask" "F.Paste")
			(net "HDD13_LED_G")
			(options
				(clearance outline)
				(anchor circle)
			)
			(primitives
				(gr_poly
					(pts
						(arc
							(start -0.1778 0.5715)
							(mid -0.321484 0.511984)
							(end -0.381 0.3683)
						)
						(arc
							(start -0.381 -0.3683)
							(mid -0.321484 -0.511984)
							(end -0.1778 -0.5715)
						)
						(arc
							(start 0.1778 -0.5715)
							(mid 0.321484 -0.511984)
							(end 0.381 -0.3683)
						)
						(arc
							(start 0.381 0.3683)
							(mid 0.321484 0.511984)
							(end 0.1778 0.5715)
						)
					)
					(width 0)
					(fill yes)
				)
			)
		)
		(pad "G" smd custom
			(at -0.98425 0.9525)
			(size 0.1905 0.1905)
			(layers "F.Cu" "F.Mask" "F.Paste")
			(net "HDD13_LED_B")
			(options
				(clearance outline)
				(anchor circle)
			)
			(primitives
				(gr_poly
					(pts
						(arc
							(start -0.1778 0.5715)
							(mid -0.321484 0.511984)
							(end -0.381 0.3683)
						)
						(arc
							(start -0.381 -0.3683)
							(mid -0.321484 -0.511984)
							(end -0.1778 -0.5715)
						)
						(arc
							(start 0.1778 -0.5715)
							(mid 0.321484 -0.511984)
							(end 0.381 -0.3683)
						)
						(arc
							(start 0.381 0.3683)
							(mid 0.321484 0.511984)
							(end 0.1778 0.5715)
						)
					)
					(width 0)
					(fill yes)
				)
			)
		)
		(pad "S" smd custom
			(at 0.98425 0.9525)
			(size 0.1905 0.1905)
			(layers "F.Cu" "F.Mask" "F.Paste")
			(net "GND")
			(options
				(clearance outline)
				(anchor circle)
			)
			(primitives
				(gr_poly
					(pts
						(arc
							(start -0.1778 0.5715)
							(mid -0.321484 0.511984)
							(end -0.381 0.3683)
						)
						(arc
							(start -0.381 -0.3683)
							(mid -0.321484 -0.511984)
							(end -0.1778 -0.5715)
						)
						(arc
							(start 0.1778 -0.5715)
							(mid 0.321484 -0.511984)
							(end 0.381 -0.3683)
						)
						(arc
							(start 0.381 0.3683)
							(mid 0.321484 0.511984)
							(end 0.1778 0.5715)
						)
					)
					(width 0)
					(fill yes)
				)
			)
		)
	)
	(footprint ""
		(layer "F.Cu")
		(at 21.082 -256.159 -90)
		(property "Reference" "R269"
			(at 0 0 270)
			(layer "F.SilkS")
			(hide yes)
			(effects
				(font
					(size 1.27 1.27)
				)
			)
		)
		(property "Value" "402R2F-GP"
			(at 0.064008 -3.993896 270)
			(unlocked yes)
			(layer "F.Fab")
			(hide yes)
			(effects
				(font
					(size 1.016 1.016)
					(thickness 0.1524)
				)
			)
		)
		(property "Device Type" "R402H16"
			(at 0.064008 -5.517896 270)
			(unlocked yes)
			(layer "F.Fab")
			(hide yes)
			(effects
				(font
					(size 1.016 1.016)
					(thickness 0.1524)
				)
			)
		)
		(duplicate_pad_numbers_are_jumpers no)
		(fp_line
			(start -0.508 -0.9398)
			(end -0.508 0.9398)
			(stroke
				(width 0.1524)
				(type default)
			)
			(layer "F.SilkS")
		)
		(fp_line
			(start 0.508 -0.9398)
			(end -0.508 -0.9398)
			(stroke
				(width 0.1524)
				(type default)
			)
			(layer "F.SilkS")
		)
		(fp_rect
			(start -0.508 0.9398)
			(end 0.508 -0.9398)
			(stroke
				(width 0)
				(type default)
			)
			(fill no)
			(layer "F.CrtYd")
		)
		(fp_rect
			(start -0.508 0.9398)
			(end 0.508 -0.9398)
			(stroke
				(width 0)
				(type default)
			)
			(fill no)
			(layer "F.Fab")
		)
		(pad "1" smd custom
			(at 0 -0.4445 270)
			(size 0.1397 0.1397)
			(layers "F.Cu" "F.Mask" "F.Paste")
			(net "P5VC_HDD12_LED")
			(options
				(clearance outline)
				(anchor circle)
			)
			(primitives
				(gr_poly
					(pts
						(arc
							(start -0.1778 -0.2794)
							(mid -0.249642 -0.249642)
							(end -0.2794 -0.1778)
						)
						(arc
							(start -0.2794 0.1778)
							(mid -0.249642 0.249642)
							(end -0.1778 0.2794)
						)
						(arc
							(start 0.1778 0.2794)
							(mid 0.249642 0.249642)
							(end 0.2794 0.1778)
						)
						(arc
							(start 0.2794 -0.1778)
							(mid 0.249642 -0.249642)
							(end 0.1778 -0.2794)
						)
					)
					(width 0)
					(fill yes)
				)
			)
		)
		(pad "2" smd custom
			(at 0 0.4445 270)
			(size 0.1397 0.1397)
			(layers "F.Cu" "F.Mask" "F.Paste")
			(net "DRV_ACT_12")
			(options
				(clearance outline)
				(anchor circle)
			)
			(primitives
				(gr_poly
					(pts
						(arc
							(start -0.1778 -0.2794)
							(mid -0.249642 -0.249642)
							(end -0.2794 -0.1778)
						)
						(arc
							(start -0.2794 0.1778)
							(mid -0.249642 0.249642)
							(end -0.1778 0.2794)
						)
						(arc
							(start 0.1778 0.2794)
							(mid 0.249642 0.249642)
							(end 0.2794 0.1778)
						)
						(arc
							(start 0.2794 -0.1778)
							(mid 0.249642 -0.249642)
							(end 0.1778 -0.2794)
						)
					)
					(width 0)
					(fill yes)
				)
			)
		)
	)
	(footprint ""
		(layer "F.Cu")
		(at 46.7106 -234.188)
		(property "Reference" "Q71"
			(at 0 0 0)
			(layer "F.SilkS")
			(hide yes)
			(effects
				(font
					(size 1.27 1.27)
				)
			)
		)
		(property "Value" "2N7002-11-GP"
			(at 0.127 -8.9662 0)
			(unlocked yes)
			(layer "F.Fab")
			(hide yes)
			(effects
				(font
					(size 1.016 1.016)
					(thickness 0.1524)
				)
			)
		)
		(property "Device Type" "SOT23DGS2D4H44"
			(at 0.127 -10.4902 0)
			(unlocked yes)
			(layer "F.Fab")
			(hide yes)
			(effects
				(font
					(size 1.016 1.016)
					(thickness 0.1524)
				)
			)
		)
		(duplicate_pad_numbers_are_jumpers no)
		(fp_line
			(start -1.651 -1.778)
			(end -1.651 1.778)
			(stroke
				(width 0.1524)
				(type default)
			)
			(layer "F.SilkS")
		)
		(fp_line
			(start -1.651 1.778)
			(end 1.651 1.778)
			(stroke
				(width 0.1524)
				(type default)
			)
			(layer "F.SilkS")
		)
		(fp_line
			(start 1.651 -1.778)
			(end -1.651 -1.778)
			(stroke
				(width 0.1524)
				(type default)
			)
			(layer "F.SilkS")
		)
		(fp_line
			(start 1.651 1.778)
			(end 1.651 -1.778)
			(stroke
				(width 0.1524)
				(type default)
			)
			(layer "F.SilkS")
		)
		(fp_poly
			(pts
				(xy -1.778 1.8796) (xy -1.778 -1.8796) (xy 1.778 -1.8796) (xy 1.778 1.8796)
			)
			(stroke
				(width 0)
				(type default)
			)
			(fill no)
			(layer "F.CrtYd")
		)
		(fp_poly
			(pts
				(xy -1.778 1.8796) (xy -1.778 -1.8796) (xy 1.778 -1.8796) (xy 1.778 1.8796)
			)
			(stroke
				(width 0)
				(type default)
			)
			(fill no)
			(layer "F.Fab")
		)
		(pad "D" smd custom
			(at 0 -0.9525)
			(size 0.1905 0.1905)
			(layers "F.Cu" "F.Mask" "F.Paste")
			(net "HDD12_LED_G")
			(options
				(clearance outline)
				(anchor circle)
			)
			(primitives
				(gr_poly
					(pts
						(arc
							(start -0.1778 0.5715)
							(mid -0.321484 0.511984)
							(end -0.381 0.3683)
						)
						(arc
							(start -0.381 -0.3683)
							(mid -0.321484 -0.511984)
							(end -0.1778 -0.5715)
						)
						(arc
							(start 0.1778 -0.5715)
							(mid 0.321484 -0.511984)
							(end 0.381 -0.3683)
						)
						(arc
							(start 0.381 0.3683)
							(mid 0.321484 0.511984)
							(end 0.1778 0.5715)
						)
					)
					(width 0)
					(fill yes)
				)
			)
		)
		(pad "G" smd custom
			(at -0.98425 0.9525)
			(size 0.1905 0.1905)
			(layers "F.Cu" "F.Mask" "F.Paste")
			(net "HDD12_LED_B")
			(options
				(clearance outline)
				(anchor circle)
			)
			(primitives
				(gr_poly
					(pts
						(arc
							(start -0.1778 0.5715)
							(mid -0.321484 0.511984)
							(end -0.381 0.3683)
						)
						(arc
							(start -0.381 -0.3683)
							(mid -0.321484 -0.511984)
							(end -0.1778 -0.5715)
						)
						(arc
							(start 0.1778 -0.5715)
							(mid 0.321484 -0.511984)
							(end 0.381 -0.3683)
						)
						(arc
							(start 0.381 0.3683)
							(mid 0.321484 0.511984)
							(end 0.1778 0.5715)
						)
					)
					(width 0)
					(fill yes)
				)
			)
		)
		(pad "S" smd custom
			(at 0.98425 0.9525)
			(size 0.1905 0.1905)
			(layers "F.Cu" "F.Mask" "F.Paste")
			(net "GND")
			(options
				(clearance outline)
				(anchor circle)
			)
			(primitives
				(gr_poly
					(pts
						(arc
							(start -0.1778 0.5715)
							(mid -0.321484 0.511984)
							(end -0.381 0.3683)
						)
						(arc
							(start -0.381 -0.3683)
							(mid -0.321484 -0.511984)
							(end -0.1778 -0.5715)
						)
						(arc
							(start 0.1778 -0.5715)
							(mid 0.321484 -0.511984)
							(end 0.381 -0.3683)
						)
						(arc
							(start 0.381 0.3683)
							(mid 0.321484 0.511984)
							(end 0.1778 0.5715)
						)
					)
					(width 0)
					(fill yes)
				)
			)
		)
	)
	(footprint ""
		(layer "F.Cu")
		(at 14.097 -187.706 90)
		(property "Reference" "C351"
			(at 0 0 90)
			(layer "F.SilkS")
			(hide yes)
			(effects
				(font
					(size 1.27 1.27)
				)
			)
		)
		(property "Value" "SC10U25V5KX-GP"
			(at -0.0762 -6.1214 90)
			(unlocked yes)
			(layer "F.Fab")
			(hide yes)
			(effects
				(font
					(size 1.016 1.016)
					(thickness 0.1524)
				)
			)
		)
		(property "Device Type" "C805H56"
			(at -0.0762 -8.1534 90)
			(unlocked yes)
			(layer "F.Fab")
			(hide yes)
			(effects
				(font
					(size 1.016 1.016)
					(thickness 0.1524)
				)
			)
		)
		(duplicate_pad_numbers_are_jumpers no)
		(fp_line
			(start 0.635 0)
			(end -0.635 0)
			(stroke
				(width 0.508)
				(type default)
			)
			(layer "F.SilkS")
		)
		(fp_rect
			(start -0.9652 1.778)
			(end 0.9652 -1.778)
			(stroke
				(width 0)
				(type default)
			)
			(fill no)
			(layer "F.CrtYd")
		)
		(fp_poly
			(pts
				(xy -0.9652 -1.778) (xy 0.9652 -1.778) (xy 0.9652 1.778) (xy -0.9652 1.778)
			)
			(stroke
				(width 0)
				(type default)
			)
			(fill no)
			(layer "F.Fab")
		)
		(pad "1" smd rect
			(at 0 -0.9652 90)
			(size 1.397 1.143)
			(layers "F.Cu" "F.Mask" "F.Paste")
			(net "P12V")
		)
		(pad "2" smd rect
			(at 0 0.9652 90)
			(size 1.397 1.143)
			(layers "F.Cu" "F.Mask" "F.Paste")
			(net "GND")
		)
	)
	(footprint ""
		(layer "F.Cu")
		(at 57.911746 -176.1617 -90)
		(property "Reference" "R217"
			(at 0 0 270)
			(layer "F.SilkS")
			(hide yes)
			(effects
				(font
					(size 1.27 1.27)
				)
			)
		)
		(property "Value" "4K7R2J-2-GP"
			(at 0.064008 -3.993896 270)
			(unlocked yes)
			(layer "F.Fab")
			(hide yes)
			(effects
				(font
					(size 1.016 1.016)
					(thickness 0.1524)
				)
			)
		)
		(property "Device Type" "R402H16"
			(at 0.064008 -5.517896 270)
			(unlocked yes)
			(layer "F.Fab")
			(hide yes)
			(effects
				(font
					(size 1.016 1.016)
					(thickness 0.1524)
				)
			)
		)
		(duplicate_pad_numbers_are_jumpers no)
		(fp_line
			(start -0.508 -0.9398)
			(end -0.508 0.9398)
			(stroke
				(width 0.1524)
				(type default)
			)
			(layer "F.SilkS")
		)
		(fp_line
			(start 0.508 -0.9398)
			(end -0.508 -0.9398)
			(stroke
				(width 0.1524)
				(type default)
			)
			(layer "F.SilkS")
		)
		(fp_rect
			(start -0.508 0.9398)
			(end 0.508 -0.9398)
			(stroke
				(width 0)
				(type default)
			)
			(fill no)
			(layer "F.CrtYd")
		)
		(fp_rect
			(start -0.508 0.9398)
			(end 0.508 -0.9398)
			(stroke
				(width 0)
				(type default)
			)
			(fill no)
			(layer "F.Fab")
		)
		(pad "1" smd custom
			(at 0 -0.4445 270)
			(size 0.1397 0.1397)
			(layers "F.Cu" "F.Mask" "F.Paste")
			(net "P3V3")
			(options
				(clearance outline)
				(anchor circle)
			)
			(primitives
				(gr_poly
					(pts
						(arc
							(start -0.1778 -0.2794)
							(mid -0.249642 -0.249642)
							(end -0.2794 -0.1778)
						)
						(arc
							(start -0.2794 0.1778)
							(mid -0.249642 0.249642)
							(end -0.1778 0.2794)
						)
						(arc
							(start 0.1778 0.2794)
							(mid 0.249642 0.249642)
							(end 0.2794 0.1778)
						)
						(arc
							(start 0.2794 -0.1778)
							(mid 0.249642 -0.249642)
							(end 0.1778 -0.2794)
						)
					)
					(width 0)
					(fill yes)
				)
			)
		)
		(pad "2" smd custom
			(at 0 0.4445 270)
			(size 0.1397 0.1397)
			(layers "F.Cu" "F.Mask" "F.Paste")
			(net "HDD_PRSNT_NET8")
			(options
				(clearance outline)
				(anchor circle)
			)
			(primitives
				(gr_poly
					(pts
						(arc
							(start -0.1778 -0.2794)
							(mid -0.249642 -0.249642)
							(end -0.2794 -0.1778)
						)
						(arc
							(start -0.2794 0.1778)
							(mid -0.249642 0.249642)
							(end -0.1778 0.2794)
						)
						(arc
							(start 0.1778 0.2794)
							(mid 0.249642 0.249642)
							(end 0.2794 0.1778)
						)
						(arc
							(start 0.2794 -0.1778)
							(mid 0.249642 -0.249642)
							(end 0.1778 -0.2794)
						)
					)
					(width 0)
					(fill yes)
				)
			)
		)
	)
	(footprint ""
		(layer "F.Cu")
		(at 75.057 -84.074 180)
		(property "Reference" "C245"
			(at 0 0 180)
			(layer "F.SilkS")
			(hide yes)
			(effects
				(font
					(size 1.27 1.27)
				)
			)
		)
		(property "Value" "SCD1U10V2KX-5GP"
			(at 1.1811 -2.7051 180)
			(unlocked yes)
			(layer "F.Fab")
			(hide yes)
			(effects
				(font
					(size 1.016 1.016)
					(thickness 0.1524)
				)
			)
		)
		(property "Device Type" "C402H22"
			(at 1.1811 -4.2291 180)
			(unlocked yes)
			(layer "F.Fab")
			(hide yes)
			(effects
				(font
					(size 1.016 1.016)
					(thickness 0.1524)
				)
			)
		)
		(duplicate_pad_numbers_are_jumpers no)
		(fp_rect
			(start -0.4318 0.9525)
			(end 0.4318 -0.9525)
			(stroke
				(width 0)
				(type default)
			)
			(fill no)
			(layer "F.CrtYd")
		)
		(fp_rect
			(start -0.4318 0.9525)
			(end 0.4318 -0.9525)
			(stroke
				(width 0)
				(type default)
			)
			(fill no)
			(layer "F.Fab")
		)
		(pad "1" smd custom
			(at 0 -0.4445 180)
			(size 0.1524 0.1524)
			(layers "F.Cu" "F.Mask" "F.Paste")
			(net "P3V3")
			(options
				(clearance outline)
				(anchor circle)
			)
			(primitives
				(gr_poly
					(pts
						(arc
							(start 0.3048 -0.2032)
							(mid 0.275042 -0.275042)
							(end 0.2032 -0.3048)
						)
						(arc
							(start -0.2032 -0.3048)
							(mid -0.275042 -0.275042)
							(end -0.3048 -0.2032)
						)
						(arc
							(start -0.3048 0.2032)
							(mid -0.275042 0.275042)
							(end -0.2032 0.3048)
						)
						(arc
							(start 0.2032 0.3048)
							(mid 0.275042 0.275042)
							(end 0.3048 0.2032)
						)
					)
					(width 0)
					(fill yes)
				)
			)
		)
		(pad "2" smd custom
			(at 0 0.4445 180)
			(size 0.1524 0.1524)
			(layers "F.Cu" "F.Mask" "F.Paste")
			(net "GND")
			(options
				(clearance outline)
				(anchor circle)
			)
			(primitives
				(gr_poly
					(pts
						(arc
							(start 0.3048 -0.2032)
							(mid 0.275042 -0.275042)
							(end 0.2032 -0.3048)
						)
						(arc
							(start -0.2032 -0.3048)
							(mid -0.275042 -0.275042)
							(end -0.3048 -0.2032)
						)
						(arc
							(start -0.3048 0.2032)
							(mid -0.275042 0.275042)
							(end -0.2032 0.3048)
						)
						(arc
							(start 0.2032 0.3048)
							(mid 0.275042 0.275042)
							(end 0.3048 0.2032)
						)
					)
					(width 0)
					(fill yes)
				)
			)
		)
	)
	(footprint ""
		(layer "F.Cu")
		(at 10.159746 -467.8807 90)
		(property "Reference" "R392"
			(at 0 0 90)
			(layer "F.SilkS")
			(hide yes)
			(effects
				(font
					(size 1.27 1.27)
				)
			)
		)
		(property "Value" "0R2J-2-GP"
			(at 0.064008 -3.993896 90)
			(unlocked yes)
			(layer "F.Fab")
			(hide yes)
			(effects
				(font
					(size 1.016 1.016)
					(thickness 0.1524)
				)
			)
		)
		(property "Device Type" "R402H16"
			(at 0.064008 -5.517896 90)
			(unlocked yes)
			(layer "F.Fab")
			(hide yes)
			(effects
				(font
					(size 1.016 1.016)
					(thickness 0.1524)
				)
			)
		)
		(duplicate_pad_numbers_are_jumpers no)
		(fp_line
			(start 0.508 -0.9398)
			(end -0.508 -0.9398)
			(stroke
				(width 0.1524)
				(type default)
			)
			(layer "F.SilkS")
		)
		(fp_line
			(start -0.508 -0.9398)
			(end -0.508 0.9398)
			(stroke
				(width 0.1524)
				(type default)
			)
			(layer "F.SilkS")
		)
		(fp_rect
			(start -0.508 0.9398)
			(end 0.508 -0.9398)
			(stroke
				(width 0)
				(type default)
			)
			(fill no)
			(layer "F.CrtYd")
		)
		(fp_rect
			(start -0.508 0.9398)
			(end 0.508 -0.9398)
			(stroke
				(width 0)
				(type default)
			)
			(fill no)
			(layer "F.Fab")
		)
		(pad "1" smd custom
			(at 0 -0.4445 90)
			(size 0.1397 0.1397)
			(layers "F.Cu" "F.Mask" "F.Paste")
			(net "EXP_A_PRNST_TX")
			(options
				(clearance outline)
				(anchor circle)
			)
			(primitives
				(gr_poly
					(pts
						(arc
							(start -0.1778 -0.2794)
							(mid -0.249642 -0.249642)
							(end -0.2794 -0.1778)
						)
						(arc
							(start -0.2794 0.1778)
							(mid -0.249642 0.249642)
							(end -0.1778 0.2794)
						)
						(arc
							(start 0.1778 0.2794)
							(mid 0.249642 0.249642)
							(end 0.2794 0.1778)
						)
						(arc
							(start 0.2794 -0.1778)
							(mid 0.249642 -0.249642)
							(end 0.1778 -0.2794)
						)
					)
					(width 0)
					(fill yes)
				)
			)
		)
		(pad "2" smd custom
			(at 0 0.4445 90)
			(size 0.1397 0.1397)
			(layers "F.Cu" "F.Mask" "F.Paste")
			(net "EXP_A_PRNST_RX")
			(options
				(clearance outline)
				(anchor circle)
			)
			(primitives
				(gr_poly
					(pts
						(arc
							(start -0.1778 -0.2794)
							(mid -0.249642 -0.249642)
							(end -0.2794 -0.1778)
						)
						(arc
							(start -0.2794 0.1778)
							(mid -0.249642 0.249642)
							(end -0.1778 0.2794)
						)
						(arc
							(start 0.1778 0.2794)
							(mid 0.249642 0.249642)
							(end 0.2794 0.1778)
						)
						(arc
							(start 0.2794 -0.1778)
							(mid 0.249642 -0.249642)
							(end 0.1778 -0.2794)
						)
					)
					(width 0)
					(fill yes)
				)
			)
		)
	)
)
